# Bryce Canyon_ME BOM MP.xlsx — Spare DVT (bom)
| Triton DVT spare parts |  |  |  |  |  |  |  |  |  |
|  | Item | Photo | Item | FB PN | WW PN | FB Description | WW Description | U/P | Remark |
|  | 1 |  | IOM Module (w/ IOC) | Please apply new FB PN for DVT | B81.01110.0058 | IO MODULE W/ BMC, W/ IOC, TRITON, DVT |  | 1 |  |
|  |  |  | PCBA | Please apply new FB PN for DVT | B81.01110.0053 | PCBA, IO MODULE W/ BMC, W/ IOC, TRITON, DVT |  | 1 |  |
|  |  |  |  | ME Part | 86.00T32.544 | SCREW | SCRW WAFRE M3.0 L4 NYLOK | 11=>12 | add 1 screw for TPM |
|  |  |  |  |  | B60.0110P.0001 | IOM (IOC) bracket | ASSY IO MODULE BRACKET IOC TRITON | 1 |  |
|  |  |  | TPM | 19-000698 | B81.00X10.0085 | TPM CARD, WIWYNN |  | 1 |  |
|  |  |  | NIC | 19-000682 | 054.03118.M002 054.03028.M003 | NIC CARD, AVL, TIOGA PASS, 25G, MEZZ, DVT, WISTRON |  | 1 |  |
|  | 2 |  | IOM module (M.2) | Please apply new FB PN for DVT | B81.01110.0059 | IO MODULE W/ BMC, W/O IOC, TRITON, DVT |  |  |  |
|  |  |  | PCBA | Please apply new FB PN for DVT | B81.01110.0047 | PCBA, IO MODULE W/ BMC, W/O IOC, TRITON, DVT |  |  |  |
|  |  |  |  | ME Part | 86.00T32.544 | SCREW | SCRW WAFRE M3.0 L4 NYLOK | 13=>14 | add 1 screw for TPM |
|  |  |  |  |  | B60.0110O.0001 | IOM (M.2) bracket | ASSY IO MODULE BRACKET M.2 TRITON | 1 |  |
|  |  |  |  |  | B47.0111N.0001 | IOM M.2 Air Baffle Mylar | MYLAR+SPONGE IOM M2 AIR BAFFLE TRITON | 1 |  |
|  |  |  | TPM | 19-000698 | B81.00X10.0085 | TPM CARD, WIWYNN |  | 2 |  |
|  |  |  | NIC | 19-000682 | 054.03118.M002 054.03028.M003 | NIC CARD, AVL, TIOGA PASS, 25G, MEZZ, DVT, WISTRON |  | 2 |  |
|  |  |  | M.2 | 09-000523 | 056.02030.M002 056.02018.M018 056.02030.M003 | FLASH CARD, 256GB, M.2 PCIE SSD, DVT, WISTRON |  | 2 |  |
|  | 3 |  | SCC Module W/IOC | Please apply new FB PN for DVT | B81.01110.0046 (Same parts, same PN) | STORAGE CONTROLLER CARD, BROADCOM, W/ EXPANDER, W/ IOC, TRITON, DVT |  | 1 |  |
|  |  |  | PCBA | Please apply new FB PN for DVT |  | PCBA, STORAGE CONTROLLER CARD, BROADCOM, W/ EXPANDER, W/ IOC, TRITON, EVT2 |  |  |  |
|  |  |  |  | ME Part | B33.01112.0001 | Stiffener | BRKT SCC STIFFERNER TRITON | 1 | Cancel at DVT |
|  |  |  |  |  | B42.0111G.0001 | New Right SCC latch | LATCH SCC R TRITON | 1 |  |
|  |  |  |  |  | B42.0111H.0001 | New Left SCC latch | LATCH SCC L TRITON | 1 |  |
|  |  |  |  |  | 86.00T32.544 | SCREW | SCRW WAFRE M3.0 L4 NYLOK | 2 | Cancel at DVT |
|  | 4 |  | SCC Module W/O IOC | Please apply new FB PN for DVT | B81.01110.0052 | STORAGE CONTROLLER CARD, BROADCOM, W/ EXPANDER, W/O IOC, TRITON, DVT |  | 1 |  |
|  |  |  | PCBA | Please apply new FB PN for DVT |  | PCBA, STORAGE CONTROLLER CARD, BROADCOM, W/ EXPANDER, W/O IOC, TRITON, EVT2 |  |  |  |
|  |  |  |  | ME Part | B33.01112.0001 | Stiffener | BRKT SCC STIFFERNER TRITON | 1 | Cancel at DVT |
|  |  |  |  |  | B42.0111G.0001 | New Right SCC latch | LATCH SCC R TRITON | 1 |  |
|  |  |  |  |  | B42.0111H.0001 | New Left SCC latch | LATCH SCC L TRITON | 1 |  |
|  |  |  |  |  | 86.00T32.544 | SCREW | SCRW WAFRE M3.0 L4 NYLOK | 2 | Cancel at DVT |
|  | 4 |  | DPB | Please apply new FB PN for DVT | B81.01110.0060 | DRIVE PLANE BOARD ASSY, TRITON, DVT |  | 1 |  |
|  |  |  | PCBA | FDPB | Same |  |  | 1 |  |
|  |  |  |  | RDPB | Same |  |  | 1 |  |
|  |  |  | ME Part | ME Part | B42.0110Z.0001 | DPB SUPPORT AIR DUCT | DPB SUPPORT AIR DUCT | 2 |  |
|  |  |  |  |  | B42.0111O.0001 | CVR DPB BAFFLE DVT BRYCE CANYON | CVR DPB BAFFLE DVT BRYCE CANYON | 1 |  |
|  |  |  |  |  | 86.00Q25.547 | SCREW | SCRW CAP M3*5L NI NYLOK | 24 |  |
|  |  |  |  |  | B47.0112H.0001 | FRONT DPB SEAL Mylar | MYLAR DPB SEAL DVT BC | 1 |  |
|  |  |  | FDPB Module -1 | Please apply new FB PN for DVT | B81.01110.0048 (Same parts, same PN) | DRIVE PLANE BOARD, FRONT, TRITON, DVT |  | 1 |  |
|  |  |  |  |  |  | PCBA, DRIVE PLANE BOARD, FRONT, TRITON, DVT |  |  |  |
|  |  |  | PCBA | ME Part | B42.0110D.0001 | IOM mid card guide | IOM CARD GUIDE SIDE TRITON KY | 2 |  |
|  |  |  |  |  | B42.0110C.0001 | IOM mid card guide | IOM CARD GUIDE MID TRITON KY | 1 |  |
|  |  |  |  |  | 086.AA522.05R0 | Screw for card guide | SCRW TAP WEFER M2*L5 NI | 8 |  |
|  |  |  |  |  | 086.9A554.02R0 | SCREW | SCRW WAFER M3X0.5 L2 NI NYLOK | 4 |  |
|  |  |  |  |  | B34.0110P.0001 | FDPB support BKT | FDPB SUPPORT | 4 |  |
|  |  |  | RDPB Module -2 | Please apply new FB PN for DVT | B81.01110.0049 (Same parts, same PN) | DRIVE PLANE BOARD, REAR, TRITON, DVT |  | 1 |  |
|  |  |  |  |  |  | PCBA, DRIVE PLANE BOARD, REAR, TRITON, DVT |  |  |  |
|  |  |  | PCBA | ME Part |  |  |  |  |  |
|  | 5 |  | Bus Bar Module |  | B81.01128.0002 | BUS BAR CABLE DVT MODULE |  |  | ok |
|  |  |  | Cable |  | B50.0110U.0001 | C.A. BAR CABLE DVT FCI | C.A. BAR CABLE DVT FCI | 1 |  |
|  |  |  |  |  | B42.0111F.0001 | HLDR TRACK CABLE GULY-5AB-29F DVT | HLDR TRACK CABLE GULY-5AB-29F DVT | 1 |  |
|  |  |  |  |  | 086.000J7.0586 | SCREW | SCRW FLT M5X0.8 L6 NI NYLOK | 4 | in accessory package |
|  |  |  |  |  | 86.6C536.8R0 | SCREW | SCRW M4X8 PH MS+E+N | 1 | in accessory package |
|  | 6 |  | Fan Module | 05-000264 | B81.01115.0001 | FAN, 92MM, TRITON |  |  | Provide fan cage PN on 3/24. |
|  |  |  | Fan |  | 023.1006X.0001 | Fan | FAN VG92561BX SUNON 92X92X56MM 6P | 2 |  |
|  |  |  | ME Part |  | B47.0112I.0001 | RUB RUB FAN MOUNT BRYCE CANYON | RUB FAN MOUNT SR-21Y-WTB | 8 |  |
|  |  |  |  |  | B60.01107.0001 | Fan cage | ASSY FAN CAGE | 1 |  |
|  | 7 |  | Mono-lake Module | 01-002330 | 054.25096.M001 | SERVER BOARD, TRITON TYPE 5, MONO LAKE, 16C, EVT |  |  |  |
|  |  |  | ME Part |  | B47.0111A.0001 | MONO LAKE MYLAR SPONGE | MONOLAKE SPONGE | 1 |  |
